(kicad_pcb
	(version 20260206)
	(generator "pcbnew")
	(generator_version "10.0")
	(general
		(thickness 1.6)
		(legacy_teardrops no)
	)
	(paper "A4")
	(title_block
		(title "04192023_DAF0TMB3IC0_F0TG_MB_C_brd_V02_OCP.brd")
		(comment 1 "Grand Teton / footprints 712-718 of 8354")
	)
	(layers
		(0 "F.Cu" signal "TOP")
		(4 "In1.Cu" signal "GND")
		(6 "In2.Cu" signal "IN1")
		(8 "In3.Cu" signal "GND1")
		(10 "In4.Cu" signal "IN2")
		(12 "In5.Cu" signal "GND2")
		(14 "In6.Cu" signal "IN3")
		(16 "In7.Cu" signal "GND3")
		(18 "In8.Cu" signal "VCC")
		(20 "In9.Cu" signal "VCC1")
		(22 "In10.Cu" signal "GND4")
		(24 "In11.Cu" signal "IN4")
		(26 "In12.Cu" signal "GND5")
		(28 "In13.Cu" signal "IN5")
		(30 "In14.Cu" signal "GND6")
		(32 "In15.Cu" signal "IN6")
		(34 "In16.Cu" signal "GND7")
		(2 "B.Cu" signal "BOTTOM")
		(9 "F.Adhes" user "F.Adhesive")
		(11 "B.Adhes" user "B.Adhesive")
		(13 "F.Paste" user "Package Geometry/Pastemask Top")
		(15 "B.Paste" user "Package Geometry/Pastemask Bottom")
		(5 "F.SilkS" user "Ref Des/Silkscreen Top")
		(7 "B.SilkS" user "Ref Des/Silkscreen Bottom")
		(1 "F.Mask" user "Board Geometry/Soldermask Top")
		(3 "B.Mask" user "Board Geometry/Soldermask Bottom")
		(17 "Dwgs.User" user "User.Drawings")
		(19 "Cmts.User" user "User.Comments")
		(21 "Eco1.User" user "User.Eco1")
		(23 "Eco2.User" user "User.Eco2")
		(25 "Edge.Cuts" user "Board Geometry/Outline")
		(27 "Margin" user)
		(31 "F.CrtYd" user "Package Geometry/Place Bound Top")
		(29 "B.CrtYd" user "Package Geometry/Place Bound Bottom")
		(35 "F.Fab" user "Ref Des/Assembly Top")
		(33 "B.Fab" user "Ref Des/Assembly Bottom")
	)
	(footprint ""
		(layer "F.Cu")
		(at 34.665158 -172.53966)
		(property "Reference" "R5011"
			(at 0 0 0)
			(layer "F.SilkS")
			(hide yes)
			(effects
				(font
					(size 1.27 1.27)
				)
			)
		)
		(property "Value" ""
			(at 0 0 0)
			(layer "F.Fab")
			(effects
				(font
					(size 1.27 1.27)
				)
			)
		)
		(duplicate_pad_numbers_are_jumpers no)
		(fp_line
			(start -0.7874 -0.4064)
			(end 0.7874 -0.4064)
			(stroke
				(width 0.1524)
				(type default)
			)
			(layer "F.SilkS")
		)
		(fp_line
			(start -0.7874 0.4064)
			(end -0.7874 -0.4064)
			(stroke
				(width 0.1524)
				(type default)
			)
			(layer "F.SilkS")
		)
		(fp_line
			(start 0.7874 -0.4064)
			(end 0.7874 0.4064)
			(stroke
				(width 0.1524)
				(type default)
			)
			(layer "F.SilkS")
		)
		(fp_line
			(start 0.7874 0.4064)
			(end -0.7874 0.4064)
			(stroke
				(width 0.1524)
				(type default)
			)
			(layer "F.SilkS")
		)
		(fp_line
			(start -0.67945 -0.305054)
			(end -0.12065 -0.305054)
			(stroke
				(width 0.1)
				(type default)
			)
			(layer "F.Fab")
		)
		(fp_line
			(start -0.67945 0.3048)
			(end -0.67945 -0.305054)
			(stroke
				(width 0.1)
				(type default)
			)
			(layer "F.Fab")
		)
		(fp_line
			(start -0.12065 -0.305054)
			(end -0.12065 -0.2794)
			(stroke
				(width 0.1)
				(type default)
			)
			(layer "F.Fab")
		)
		(fp_line
			(start -0.12065 -0.2794)
			(end 0.12065 -0.2794)
			(stroke
				(width 0.1)
				(type default)
			)
			(layer "F.Fab")
		)
		(fp_line
			(start -0.12065 0.2794)
			(end -0.12065 0.3048)
			(stroke
				(width 0.1)
				(type default)
			)
			(layer "F.Fab")
		)
		(fp_line
			(start -0.12065 0.3048)
			(end -0.67945 0.3048)
			(stroke
				(width 0.1)
				(type default)
			)
			(layer "F.Fab")
		)
		(fp_line
			(start 0.120396 0.2794)
			(end -0.12065 0.2794)
			(stroke
				(width 0.1)
				(type default)
			)
			(layer "F.Fab")
		)
		(fp_line
			(start 0.120396 0.3048)
			(end 0.120396 0.2794)
			(stroke
				(width 0.1)
				(type default)
			)
			(layer "F.Fab")
		)
		(fp_line
			(start 0.12065 -0.3048)
			(end 0.67945 -0.3048)
			(stroke
				(width 0.1)
				(type default)
			)
			(layer "F.Fab")
		)
		(fp_line
			(start 0.12065 -0.2794)
			(end 0.12065 -0.3048)
			(stroke
				(width 0.1)
				(type default)
			)
			(layer "F.Fab")
		)
		(fp_line
			(start 0.67945 -0.3048)
			(end 0.67945 0.3048)
			(stroke
				(width 0.1)
				(type default)
			)
			(layer "F.Fab")
		)
		(fp_line
			(start 0.67945 0.3048)
			(end 0.120396 0.3048)
			(stroke
				(width 0.1)
				(type default)
			)
			(layer "F.Fab")
		)
		(pad "1" smd circle
			(at -0.40005 0)
			(size 0 0)
			(layers "F.Cu" "F.Mask" "F.Paste")
			(net "PVDD11_S3_P1")
		)
		(pad "2" smd circle
			(at 0.40005 0)
			(size 0 0)
			(layers "F.Cu" "F.Mask" "F.Paste")
			(net "I3C_SPD_DDRAF_CPU1_LVC1_SDA")
		)
	)
	(footprint ""
		(layer "F.Cu")
		(at 367.996978 -175.106076 -90)
		(property "Reference" "PC475"
			(at 0 0 270)
			(layer "F.SilkS")
			(hide yes)
			(effects
				(font
					(size 1.27 1.27)
				)
			)
		)
		(property "Value" ""
			(at 0 0 270)
			(layer "F.Fab")
			(effects
				(font
					(size 1.27 1.27)
				)
			)
		)
		(duplicate_pad_numbers_are_jumpers no)
		(fp_line
			(start -0.7874 0.4064)
			(end -0.7874 -0.4064)
			(stroke
				(width 0.1524)
				(type default)
			)
			(layer "F.SilkS")
		)
		(fp_line
			(start -0.255524 0.4064)
			(end -0.7874 0.4064)
			(stroke
				(width 0.1524)
				(type default)
			)
			(layer "F.SilkS")
		)
		(fp_line
			(start 0.7874 0.4064)
			(end 0.404876 0.4064)
			(stroke
				(width 0.1524)
				(type default)
			)
			(layer "F.SilkS")
		)
		(fp_line
			(start -0.7874 -0.4064)
			(end 0.7874 -0.4064)
			(stroke
				(width 0.1524)
				(type default)
			)
			(layer "F.SilkS")
		)
		(fp_line
			(start 0.7874 -0.4064)
			(end 0.7874 0.4064)
			(stroke
				(width 0.1524)
				(type default)
			)
			(layer "F.SilkS")
		)
		(fp_line
			(start -0.67945 0.3048)
			(end -0.67945 -0.305054)
			(stroke
				(width 0.1)
				(type default)
			)
			(layer "F.Fab")
		)
		(fp_line
			(start -0.12065 0.3048)
			(end -0.67945 0.3048)
			(stroke
				(width 0.1)
				(type default)
			)
			(layer "F.Fab")
		)
		(fp_line
			(start 0.120396 0.3048)
			(end 0.120396 0.2794)
			(stroke
				(width 0.1)
				(type default)
			)
			(layer "F.Fab")
		)
		(fp_line
			(start 0.67945 0.3048)
			(end 0.120396 0.3048)
			(stroke
				(width 0.1)
				(type default)
			)
			(layer "F.Fab")
		)
		(fp_line
			(start -0.12065 0.2794)
			(end -0.12065 0.3048)
			(stroke
				(width 0.1)
				(type default)
			)
			(layer "F.Fab")
		)
		(fp_line
			(start 0.120396 0.2794)
			(end -0.12065 0.2794)
			(stroke
				(width 0.1)
				(type default)
			)
			(layer "F.Fab")
		)
		(fp_line
			(start -0.12065 -0.2794)
			(end 0.12065 -0.2794)
			(stroke
				(width 0.1)
				(type default)
			)
			(layer "F.Fab")
		)
		(fp_line
			(start 0.12065 -0.2794)
			(end 0.12065 -0.3048)
			(stroke
				(width 0.1)
				(type default)
			)
			(layer "F.Fab")
		)
		(fp_line
			(start 0.12065 -0.3048)
			(end 0.67945 -0.3048)
			(stroke
				(width 0.1)
				(type default)
			)
			(layer "F.Fab")
		)
		(fp_line
			(start 0.67945 -0.3048)
			(end 0.67945 0.3048)
			(stroke
				(width 0.1)
				(type default)
			)
			(layer "F.Fab")
		)
		(fp_line
			(start -0.67945 -0.305054)
			(end -0.12065 -0.305054)
			(stroke
				(width 0.1)
				(type default)
			)
			(layer "F.Fab")
		)
		(fp_line
			(start -0.12065 -0.305054)
			(end -0.12065 -0.2794)
			(stroke
				(width 0.1)
				(type default)
			)
			(layer "F.Fab")
		)
		(pad "1" smd circle
			(at -0.40005 0 270)
			(size 0 0)
			(layers "F.Cu" "F.Mask" "F.Paste")
			(net "PVDDCR_CPU0_P0_VCC1")
		)
		(pad "2" smd circle
			(at 0.40005 0 270)
			(size 0 0)
			(layers "F.Cu" "F.Mask" "F.Paste")
			(net "GND")
		)
	)
	(footprint ""
		(layer "F.Cu")
		(at 178.943 -137.632948 -90)
		(property "Reference" "R198"
			(at 0 0 270)
			(layer "F.SilkS")
			(hide yes)
			(effects
				(font
					(size 1.27 1.27)
				)
			)
		)
		(property "Value" ""
			(at 0 0 270)
			(layer "F.Fab")
			(effects
				(font
					(size 1.27 1.27)
				)
			)
		)
		(duplicate_pad_numbers_are_jumpers no)
		(fp_line
			(start -0.7874 0.4064)
			(end -0.7874 -0.4064)
			(stroke
				(width 0.1524)
				(type default)
			)
			(layer "F.SilkS")
		)
		(fp_line
			(start 0.7874 0.4064)
			(end -0.7874 0.4064)
			(stroke
				(width 0.1524)
				(type default)
			)
			(layer "F.SilkS")
		)
		(fp_line
			(start -0.7874 -0.4064)
			(end 0.7874 -0.4064)
			(stroke
				(width 0.1524)
				(type default)
			)
			(layer "F.SilkS")
		)
		(fp_line
			(start 0.7874 -0.4064)
			(end 0.7874 0.4064)
			(stroke
				(width 0.1524)
				(type default)
			)
			(layer "F.SilkS")
		)
		(fp_line
			(start -0.67945 0.3048)
			(end -0.67945 -0.305054)
			(stroke
				(width 0.1)
				(type default)
			)
			(layer "F.Fab")
		)
		(fp_line
			(start -0.12065 0.3048)
			(end -0.67945 0.3048)
			(stroke
				(width 0.1)
				(type default)
			)
			(layer "F.Fab")
		)
		(fp_line
			(start 0.120396 0.3048)
			(end 0.120396 0.2794)
			(stroke
				(width 0.1)
				(type default)
			)
			(layer "F.Fab")
		)
		(fp_line
			(start 0.67945 0.3048)
			(end 0.120396 0.3048)
			(stroke
				(width 0.1)
				(type default)
			)
			(layer "F.Fab")
		)
		(fp_line
			(start -0.12065 0.2794)
			(end -0.12065 0.3048)
			(stroke
				(width 0.1)
				(type default)
			)
			(layer "F.Fab")
		)
		(fp_line
			(start 0.120396 0.2794)
			(end -0.12065 0.2794)
			(stroke
				(width 0.1)
				(type default)
			)
			(layer "F.Fab")
		)
		(fp_line
			(start -0.12065 -0.2794)
			(end 0.12065 -0.2794)
			(stroke
				(width 0.1)
				(type default)
			)
			(layer "F.Fab")
		)
		(fp_line
			(start 0.12065 -0.2794)
			(end 0.12065 -0.3048)
			(stroke
				(width 0.1)
				(type default)
			)
			(layer "F.Fab")
		)
		(fp_line
			(start 0.12065 -0.3048)
			(end 0.67945 -0.3048)
			(stroke
				(width 0.1)
				(type default)
			)
			(layer "F.Fab")
		)
		(fp_line
			(start 0.67945 -0.3048)
			(end 0.67945 0.3048)
			(stroke
				(width 0.1)
				(type default)
			)
			(layer "F.Fab")
		)
		(fp_line
			(start -0.67945 -0.305054)
			(end -0.12065 -0.305054)
			(stroke
				(width 0.1)
				(type default)
			)
			(layer "F.Fab")
		)
		(fp_line
			(start -0.12065 -0.305054)
			(end -0.12065 -0.2794)
			(stroke
				(width 0.1)
				(type default)
			)
			(layer "F.Fab")
		)
		(pad "1" smd circle
			(at -0.40005 0 270)
			(size 0 0)
			(layers "F.Cu" "F.Mask" "F.Paste")
			(net "RST_CPU1_PERST1_N")
		)
		(pad "2" smd circle
			(at 0.40005 0 270)
			(size 0 0)
			(layers "F.Cu" "F.Mask" "F.Paste")
			(net "RST_CPU1_PERST1_R_N")
		)
	)
	(footprint ""
		(layer "F.Cu")
		(at 42.672 -170.307)
		(property "Reference" "R564"
			(at 0 0 0)
			(layer "F.SilkS")
			(hide yes)
			(effects
				(font
					(size 1.27 1.27)
				)
			)
		)
		(property "Value" ""
			(at 0 0 0)
			(layer "F.Fab")
			(effects
				(font
					(size 1.27 1.27)
				)
			)
		)
		(duplicate_pad_numbers_are_jumpers no)
		(fp_line
			(start -0.7874 -0.4064)
			(end 0.7874 -0.4064)
			(stroke
				(width 0.1524)
				(type default)
			)
			(layer "F.SilkS")
		)
		(fp_line
			(start -0.7874 0.4064)
			(end -0.7874 -0.4064)
			(stroke
				(width 0.1524)
				(type default)
			)
			(layer "F.SilkS")
		)
		(fp_line
			(start 0.7874 -0.4064)
			(end 0.7874 0.4064)
			(stroke
				(width 0.1524)
				(type default)
			)
			(layer "F.SilkS")
		)
		(fp_line
			(start 0.7874 0.4064)
			(end -0.7874 0.4064)
			(stroke
				(width 0.1524)
				(type default)
			)
			(layer "F.SilkS")
		)
		(fp_line
			(start -0.67945 -0.305054)
			(end -0.12065 -0.305054)
			(stroke
				(width 0.1)
				(type default)
			)
			(layer "F.Fab")
		)
		(fp_line
			(start -0.67945 0.3048)
			(end -0.67945 -0.305054)
			(stroke
				(width 0.1)
				(type default)
			)
			(layer "F.Fab")
		)
		(fp_line
			(start -0.12065 -0.305054)
			(end -0.12065 -0.2794)
			(stroke
				(width 0.1)
				(type default)
			)
			(layer "F.Fab")
		)
		(fp_line
			(start -0.12065 -0.2794)
			(end 0.12065 -0.2794)
			(stroke
				(width 0.1)
				(type default)
			)
			(layer "F.Fab")
		)
		(fp_line
			(start -0.12065 0.2794)
			(end -0.12065 0.3048)
			(stroke
				(width 0.1)
				(type default)
			)
			(layer "F.Fab")
		)
		(fp_line
			(start -0.12065 0.3048)
			(end -0.67945 0.3048)
			(stroke
				(width 0.1)
				(type default)
			)
			(layer "F.Fab")
		)
		(fp_line
			(start 0.120396 0.2794)
			(end -0.12065 0.2794)
			(stroke
				(width 0.1)
				(type default)
			)
			(layer "F.Fab")
		)
		(fp_line
			(start 0.120396 0.3048)
			(end 0.120396 0.2794)
			(stroke
				(width 0.1)
				(type default)
			)
			(layer "F.Fab")
		)
		(fp_line
			(start 0.12065 -0.3048)
			(end 0.67945 -0.3048)
			(stroke
				(width 0.1)
				(type default)
			)
			(layer "F.Fab")
		)
		(fp_line
			(start 0.12065 -0.2794)
			(end 0.12065 -0.3048)
			(stroke
				(width 0.1)
				(type default)
			)
			(layer "F.Fab")
		)
		(fp_line
			(start 0.67945 -0.3048)
			(end 0.67945 0.3048)
			(stroke
				(width 0.1)
				(type default)
			)
			(layer "F.Fab")
		)
		(fp_line
			(start 0.67945 0.3048)
			(end 0.120396 0.3048)
			(stroke
				(width 0.1)
				(type default)
			)
			(layer "F.Fab")
		)
		(pad "1" smd rect
			(at -0.40005 0 180)
			(size 0.4572 0.508)
			(layers "F.Cu" "F.Mask" "F.Paste")
			(net "I3C_0_SPD_DDRAF_CPU1_SCL")
		)
		(pad "2" smd rect
			(at 0.40005 0 180)
			(size 0.4572 0.508)
			(layers "F.Cu" "F.Mask" "F.Paste")
			(net "I3C_0_SPD_DDRAF_CPU1_R_SCL")
		)
	)
	(footprint ""
		(layer "F.Cu")
		(at 181.388766 -168.317418 -90)
		(property "Reference" "R1295"
			(at 0 0 270)
			(layer "F.SilkS")
			(hide yes)
			(effects
				(font
					(size 1.27 1.27)
				)
			)
		)
		(property "Value" ""
			(at 0 0 270)
			(layer "F.Fab")
			(effects
				(font
					(size 1.27 1.27)
				)
			)
		)
		(duplicate_pad_numbers_are_jumpers no)
		(fp_line
			(start -0.7874 0.4064)
			(end -0.7874 -0.4064)
			(stroke
				(width 0.1524)
				(type default)
			)
			(layer "F.SilkS")
		)
		(fp_line
			(start 0.7874 0.4064)
			(end -0.7874 0.4064)
			(stroke
				(width 0.1524)
				(type default)
			)
			(layer "F.SilkS")
		)
		(fp_line
			(start -0.7874 -0.4064)
			(end 0.7874 -0.4064)
			(stroke
				(width 0.1524)
				(type default)
			)
			(layer "F.SilkS")
		)
		(fp_line
			(start 0.7874 -0.4064)
			(end 0.7874 0.4064)
			(stroke
				(width 0.1524)
				(type default)
			)
			(layer "F.SilkS")
		)
		(fp_line
			(start -0.67945 0.3048)
			(end -0.67945 -0.305054)
			(stroke
				(width 0.1)
				(type default)
			)
			(layer "F.Fab")
		)
		(fp_line
			(start -0.12065 0.3048)
			(end -0.67945 0.3048)
			(stroke
				(width 0.1)
				(type default)
			)
			(layer "F.Fab")
		)
		(fp_line
			(start 0.120396 0.3048)
			(end 0.120396 0.2794)
			(stroke
				(width 0.1)
				(type default)
			)
			(layer "F.Fab")
		)
		(fp_line
			(start 0.67945 0.3048)
			(end 0.120396 0.3048)
			(stroke
				(width 0.1)
				(type default)
			)
			(layer "F.Fab")
		)
		(fp_line
			(start -0.12065 0.2794)
			(end -0.12065 0.3048)
			(stroke
				(width 0.1)
				(type default)
			)
			(layer "F.Fab")
		)
		(fp_line
			(start 0.120396 0.2794)
			(end -0.12065 0.2794)
			(stroke
				(width 0.1)
				(type default)
			)
			(layer "F.Fab")
		)
		(fp_line
			(start -0.12065 -0.2794)
			(end 0.12065 -0.2794)
			(stroke
				(width 0.1)
				(type default)
			)
			(layer "F.Fab")
		)
		(fp_line
			(start 0.12065 -0.2794)
			(end 0.12065 -0.3048)
			(stroke
				(width 0.1)
				(type default)
			)
			(layer "F.Fab")
		)
		(fp_line
			(start 0.12065 -0.3048)
			(end 0.67945 -0.3048)
			(stroke
				(width 0.1)
				(type default)
			)
			(layer "F.Fab")
		)
		(fp_line
			(start 0.67945 -0.3048)
			(end 0.67945 0.3048)
			(stroke
				(width 0.1)
				(type default)
			)
			(layer "F.Fab")
		)
		(fp_line
			(start -0.67945 -0.305054)
			(end -0.12065 -0.305054)
			(stroke
				(width 0.1)
				(type default)
			)
			(layer "F.Fab")
		)
		(fp_line
			(start -0.12065 -0.305054)
			(end -0.12065 -0.2794)
			(stroke
				(width 0.1)
				(type default)
			)
			(layer "F.Fab")
		)
		(pad "1" smd rect
			(at -0.40005 0 90)
			(size 0.4572 0.508)
			(layers "F.Cu" "F.Mask" "F.Paste")
			(net "I3C_SPD_DDRGL_CPU1_SCL")
		)
		(pad "2" smd rect
			(at 0.40005 0 90)
			(size 0.4572 0.508)
			(layers "F.Cu" "F.Mask" "F.Paste")
			(net "I3C_SPD_DDRGL_CPU1_LVC1_SCL")
		)
	)
	(footprint ""
		(layer "F.Cu")
		(at 157.677358 -353.245928 180)
		(property "Reference" "C5010"
			(at 0 0 180)
			(layer "F.SilkS")
			(hide yes)
			(effects
				(font
					(size 1.27 1.27)
				)
			)
		)
		(property "Value" ""
			(at 0 0 180)
			(layer "F.Fab")
			(effects
				(font
					(size 1.27 1.27)
				)
			)
		)
		(duplicate_pad_numbers_are_jumpers no)
		(fp_line
			(start 0.7874 0.4064)
			(end -0.7874 0.4064)
			(stroke
				(width 0.1524)
				(type default)
			)
			(layer "F.SilkS")
		)
		(fp_line
			(start 0.7874 -0.4064)
			(end 0.7874 0.4064)
			(stroke
				(width 0.1524)
				(type default)
			)
			(layer "F.SilkS")
		)
		(fp_line
			(start -0.7874 0.4064)
			(end -0.7874 -0.4064)
			(stroke
				(width 0.1524)
				(type default)
			)
			(layer "F.SilkS")
		)
		(fp_line
			(start -0.7874 -0.4064)
			(end 0.7874 -0.4064)
			(stroke
				(width 0.1524)
				(type default)
			)
			(layer "F.SilkS")
		)
		(fp_line
			(start 0.67945 0.3048)
			(end 0.120396 0.3048)
			(stroke
				(width 0.1)
				(type default)
			)
			(layer "F.Fab")
		)
		(fp_line
			(start 0.67945 -0.3048)
			(end 0.67945 0.3048)
			(stroke
				(width 0.1)
				(type default)
			)
			(layer "F.Fab")
		)
		(fp_line
			(start 0.12065 -0.2794)
			(end 0.12065 -0.3048)
			(stroke
				(width 0.1)
				(type default)
			)
			(layer "F.Fab")
		)
		(fp_line
			(start 0.12065 -0.3048)
			(end 0.67945 -0.3048)
			(stroke
				(width 0.1)
				(type default)
			)
			(layer "F.Fab")
		)
		(fp_line
			(start 0.120396 0.3048)
			(end 0.120396 0.2794)
			(stroke
				(width 0.1)
				(type default)
			)
			(layer "F.Fab")
		)
		(fp_line
			(start 0.120396 0.2794)
			(end -0.12065 0.2794)
			(stroke
				(width 0.1)
				(type default)
			)
			(layer "F.Fab")
		)
		(fp_line
			(start -0.12065 0.3048)
			(end -0.67945 0.3048)
			(stroke
				(width 0.1)
				(type default)
			)
			(layer "F.Fab")
		)
		(fp_line
			(start -0.12065 0.2794)
			(end -0.12065 0.3048)
			(stroke
				(width 0.1)
				(type default)
			)
			(layer "F.Fab")
		)
		(fp_line
			(start -0.12065 -0.2794)
			(end 0.12065 -0.2794)
			(stroke
				(width 0.1)
				(type default)
			)
			(layer "F.Fab")
		)
		(fp_line
			(start -0.12065 -0.305054)
			(end -0.12065 -0.2794)
			(stroke
				(width 0.1)
				(type default)
			)
			(layer "F.Fab")
		)
		(fp_line
			(start -0.67945 0.3048)
			(end -0.67945 -0.305054)
			(stroke
				(width 0.1)
				(type default)
			)
			(layer "F.Fab")
		)
		(fp_line
			(start -0.67945 -0.305054)
			(end -0.12065 -0.305054)
			(stroke
				(width 0.1)
				(type default)
			)
			(layer "F.Fab")
		)
		(pad "1" smd circle
			(at -0.40005 0 180)
			(size 0 0)
			(layers "F.Cu" "F.Mask" "F.Paste")
			(net "PVDD11_S3_P1_PMALERT")
		)
		(pad "2" smd circle
			(at 0.40005 0 180)
			(size 0 0)
			(layers "F.Cu" "F.Mask" "F.Paste")
			(net "GND")
		)
	)
	(footprint ""
		(layer "F.Cu")
		(at 173.08576 -351.825052)
		(property "Reference" "H22"
			(at -3.9116 -3.96113 0)
			(unlocked yes)
			(layer "F.SilkS")
			(effects
				(font
					(size 0.7874 0.5842)
					(thickness 0.1524)
				)
				(justify left)
			)
		)
		(property "Value" ""
			(at 0 0 0)
			(layer "F.Fab")
			(effects
				(font
					(size 1.27 1.27)
				)
			)
		)
		(duplicate_pad_numbers_are_jumpers no)
		(pad "1" thru_hole circle
			(at 0 0)
			(size 6.1976 6.1976)
			(drill 3.7338)
			(layers "*.Cu" "*.Mask")
			(remove_unused_layers no)
			(net "GND")
			(clearance -0.9779)
			(padstack
				(mode front_inner_back)
				(layer "Inner"
					(shape circle)
					(size 5.5372 5.5372)
					(clearance -0.6477)
				)
				(layer "B.Cu"
					(shape circle)
					(size 6.1976 6.1976)
					(clearance -0.9779)
				)
			)
		)
	)
)
